# T6G (Grand Teton) — schematic netlist excerpt (pin names and nets, part order shuffled) for the footprints in the layout excerpt that follows; sources: Cadence DE-HDL packaged netlist, KiCad conversion of 04192023_DAF0TMB3IC0_F0TG_MB_C_brd_V02_OCP.brd

PC593_1  Q_CAP  22UF 16V 20% X6S  pkg C0805  page 198 : A = SW_P12V_AUX_PVDDCR_SOC_P0_FLT ; B = GND
R6132  Q_RES  1K 1% EMPTY  pkg 0402LF  page 84 : A = PVDD18_S5_P0 ; B = FAB_REV_ID0
R9274  Q_RES  0 5% CHIP  pkg 0402LF  page 28 : A = CLK_100M_CPU0_CLK04_R_DN ; B = CLK_100M_CPU0_CLK04_DN

(kicad_pcb
	(version 20260206)
	(generator "pcbnew")
	(generator_version "10.0")
	(general
		(thickness 1.6)
		(legacy_teardrops no)
	)
	(paper "A4")
	(title_block
		(title "04192023_DAF0TMB3IC0_F0TG_MB_C_brd_V02_OCP.brd")
		(comment 1 "Grand Teton / footprints 5138-5140 of 8354")
	)
	(layers
		(0 "F.Cu" signal "TOP")
		(4 "In1.Cu" signal "GND")
		(6 "In2.Cu" signal "IN1")
		(8 "In3.Cu" signal "GND1")
		(10 "In4.Cu" signal "IN2")
		(12 "In5.Cu" signal "GND2")
		(14 "In6.Cu" signal "IN3")
		(16 "In7.Cu" signal "GND3")
		(18 "In8.Cu" signal "VCC")
		(20 "In9.Cu" signal "VCC1")
		(22 "In10.Cu" signal "GND4")
		(24 "In11.Cu" signal "IN4")
		(26 "In12.Cu" signal "GND5")
		(28 "In13.Cu" signal "IN5")
		(30 "In14.Cu" signal "GND6")
		(32 "In15.Cu" signal "IN6")
		(34 "In16.Cu" signal "GND7")
		(2 "B.Cu" signal "BOTTOM")
		(9 "F.Adhes" user "F.Adhesive")
		(11 "B.Adhes" user "B.Adhesive")
		(13 "F.Paste" user "Package Geometry/Pastemask Top")
		(15 "B.Paste" user "Package Geometry/Pastemask Bottom")
		(5 "F.SilkS" user "Ref Des/Silkscreen Top")
		(7 "B.SilkS" user "Ref Des/Silkscreen Bottom")
		(1 "F.Mask" user "Board Geometry/Soldermask Top")
		(3 "B.Mask" user "Board Geometry/Soldermask Bottom")
		(17 "Dwgs.User" user "User.Drawings")
		(19 "Cmts.User" user "User.Comments")
		(21 "Eco1.User" user "User.Eco1")
		(23 "Eco2.User" user "User.Eco2")
		(25 "Edge.Cuts" user "Board Geometry/Outline")
		(27 "Margin" user)
		(31 "F.CrtYd" user "Package Geometry/Place Bound Top")
		(29 "B.CrtYd" user "Package Geometry/Place Bound Bottom")
		(35 "F.Fab" user "Ref Des/Assembly Top")
		(33 "B.Fab" user "Ref Des/Assembly Bottom")
	)
	(footprint ""
		(layer "B.Cu")
		(at 373.369586 -214.523828 90)
		(property "Reference" "R9274"
			(at 0 0 90)
			(layer "B.SilkS")
			(hide yes)
			(effects
				(font
					(size 1.27 1.27)
				)
				(justify mirror)
			)
		)
		(property "Value" ""
			(at 0 0 90)
			(layer "B.Fab")
			(effects
				(font
					(size 1.27 1.27)
				)
				(justify mirror)
			)
		)
		(duplicate_pad_numbers_are_jumpers no)
		(fp_line
			(start 0.7874 -0.4064)
			(end -0.7874 -0.4064)
			(stroke
				(width 0.1524)
				(type default)
			)
			(layer "B.SilkS")
		)
		(fp_line
			(start -0.7874 -0.4064)
			(end -0.7874 -0.065786)
			(stroke
				(width 0.1524)
				(type default)
			)
			(layer "B.SilkS")
		)
		(fp_line
			(start 0.7874 0.010414)
			(end 0.7874 -0.4064)
			(stroke
				(width 0.1524)
				(type default)
			)
			(layer "B.SilkS")
		)
		(fp_line
			(start -0.351028 0.4064)
			(end 0.436372 0.4064)
			(stroke
				(width 0.1524)
				(type default)
			)
			(layer "B.SilkS")
		)
		(fp_line
			(start 0.67945 -0.305054)
			(end 0.12065 -0.305054)
			(stroke
				(width 0.1)
				(type default)
			)
			(layer "B.Fab")
		)
		(fp_line
			(start 0.12065 -0.305054)
			(end 0.12065 -0.2794)
			(stroke
				(width 0.1)
				(type default)
			)
			(layer "B.Fab")
		)
		(fp_line
			(start -0.12065 -0.3048)
			(end -0.67945 -0.3048)
			(stroke
				(width 0.1)
				(type default)
			)
			(layer "B.Fab")
		)
		(fp_line
			(start -0.67945 -0.3048)
			(end -0.67945 0.3048)
			(stroke
				(width 0.1)
				(type default)
			)
			(layer "B.Fab")
		)
		(fp_line
			(start 0.12065 -0.2794)
			(end -0.12065 -0.2794)
			(stroke
				(width 0.1)
				(type default)
			)
			(layer "B.Fab")
		)
		(fp_line
			(start -0.12065 -0.2794)
			(end -0.12065 -0.3048)
			(stroke
				(width 0.1)
				(type default)
			)
			(layer "B.Fab")
		)
		(fp_line
			(start 0.12065 0.2794)
			(end 0.12065 0.3048)
			(stroke
				(width 0.1)
				(type default)
			)
			(layer "B.Fab")
		)
		(fp_line
			(start -0.120396 0.2794)
			(end 0.12065 0.2794)
			(stroke
				(width 0.1)
				(type default)
			)
			(layer "B.Fab")
		)
		(fp_line
			(start 0.67945 0.3048)
			(end 0.67945 -0.305054)
			(stroke
				(width 0.1)
				(type default)
			)
			(layer "B.Fab")
		)
		(fp_line
			(start 0.12065 0.3048)
			(end 0.67945 0.3048)
			(stroke
				(width 0.1)
				(type default)
			)
			(layer "B.Fab")
		)
		(fp_line
			(start -0.120396 0.3048)
			(end -0.120396 0.2794)
			(stroke
				(width 0.1)
				(type default)
			)
			(layer "B.Fab")
		)
		(fp_line
			(start -0.67945 0.3048)
			(end -0.120396 0.3048)
			(stroke
				(width 0.1)
				(type default)
			)
			(layer "B.Fab")
		)
		(pad "1" smd circle
			(at 0.40005 0 270)
			(size 0 0)
			(layers "B.Cu" "B.Mask" "B.Paste")
			(net "CLK_100M_CPU0_CLK04_R_DN")
		)
		(pad "2" smd circle
			(at -0.40005 0 270)
			(size 0 0)
			(layers "B.Cu" "B.Mask" "B.Paste")
			(net "CLK_100M_CPU0_CLK04_DN")
		)
	)
	(footprint ""
		(layer "B.Cu")
		(at 395.881098 -170.458892 180)
		(property "Reference" "PC593_1"
			(at 0 0 0)
			(layer "B.SilkS")
			(hide yes)
			(effects
				(font
					(size 1.27 1.27)
				)
				(justify mirror)
			)
		)
		(property "Value" ""
			(at 0 0 0)
			(layer "B.Fab")
			(effects
				(font
					(size 1.27 1.27)
				)
				(justify mirror)
			)
		)
		(duplicate_pad_numbers_are_jumpers no)
		(fp_line
			(start 1.524 0.762)
			(end 1.524 -0.762)
			(stroke
				(width 0.1524)
				(type default)
			)
			(layer "B.SilkS")
		)
		(fp_line
			(start 1.524 -0.762)
			(end -1.524 -0.762)
			(stroke
				(width 0.1524)
				(type default)
			)
			(layer "B.SilkS")
		)
		(fp_line
			(start -1.524 0.762)
			(end 1.524 0.762)
			(stroke
				(width 0.1524)
				(type default)
			)
			(layer "B.SilkS")
		)
		(fp_line
			(start -1.524 -0.762)
			(end -1.524 0.762)
			(stroke
				(width 0.1524)
				(type default)
			)
			(layer "B.SilkS")
		)
		(fp_line
			(start 1.1049 0.724916)
			(end -1.1049 0.724916)
			(stroke
				(width 0.1)
				(type default)
			)
			(layer "B.Fab")
		)
		(fp_line
			(start 1.1049 -0.724916)
			(end 1.1049 0.724916)
			(stroke
				(width 0.1)
				(type default)
			)
			(layer "B.Fab")
		)
		(fp_line
			(start -1.1049 0.724916)
			(end -1.1049 -0.724916)
			(stroke
				(width 0.1)
				(type default)
			)
			(layer "B.Fab")
		)
		(fp_line
			(start -1.1049 -0.724916)
			(end 1.1049 -0.724916)
			(stroke
				(width 0.1)
				(type default)
			)
			(layer "B.Fab")
		)
		(pad "1" smd rect
			(at 0.889 0 180)
			(size 1.016 1.27)
			(layers "B.Cu" "B.Mask" "B.Paste")
			(net "SW_P12V_AUX_PVDDCR_SOC_P0_FLT")
		)
		(pad "2" smd rect
			(at -0.889 0 180)
			(size 1.016 1.27)
			(layers "B.Cu" "B.Mask" "B.Paste")
			(net "GND")
		)
	)
	(footprint ""
		(layer "B.Cu")
		(at 395.252194 -203.882498 -90)
		(property "Reference" "R6132"
			(at 0 0 90)
			(layer "B.SilkS")
			(hide yes)
			(effects
				(font
					(size 1.27 1.27)
				)
				(justify mirror)
			)
		)
		(property "Value" ""
			(at 0 0 90)
			(layer "B.Fab")
			(effects
				(font
					(size 1.27 1.27)
				)
				(justify mirror)
			)
		)
		(duplicate_pad_numbers_are_jumpers no)
		(fp_line
			(start -0.7874 0.4064)
			(end 0.7874 0.4064)
			(stroke
				(width 0.1524)
				(type default)
			)
			(layer "B.SilkS")
		)
		(fp_line
			(start 0.7874 0.4064)
			(end 0.7874 -0.4064)
			(stroke
				(width 0.1524)
				(type default)
			)
			(layer "B.SilkS")
		)
		(fp_line
			(start -0.7874 -0.4064)
			(end -0.7874 0.4064)
			(stroke
				(width 0.1524)
				(type default)
			)
			(layer "B.SilkS")
		)
		(fp_line
			(start 0.7874 -0.4064)
			(end -0.7874 -0.4064)
			(stroke
				(width 0.1524)
				(type default)
			)
			(layer "B.SilkS")
		)
		(fp_line
			(start -0.67945 0.3048)
			(end -0.120396 0.3048)
			(stroke
				(width 0.1)
				(type default)
			)
			(layer "B.Fab")
		)
		(fp_line
			(start -0.120396 0.3048)
			(end -0.120396 0.2794)
			(stroke
				(width 0.1)
				(type default)
			)
			(layer "B.Fab")
		)
		(fp_line
			(start 0.12065 0.3048)
			(end 0.67945 0.3048)
			(stroke
				(width 0.1)
				(type default)
			)
			(layer "B.Fab")
		)
		(fp_line
			(start 0.67945 0.3048)
			(end 0.67945 -0.305054)
			(stroke
				(width 0.1)
				(type default)
			)
			(layer "B.Fab")
		)
		(fp_line
			(start -0.120396 0.2794)
			(end 0.12065 0.2794)
			(stroke
				(width 0.1)
				(type default)
			)
			(layer "B.Fab")
		)
		(fp_line
			(start 0.12065 0.2794)
			(end 0.12065 0.3048)
			(stroke
				(width 0.1)
				(type default)
			)
			(layer "B.Fab")
		)
		(fp_line
			(start -0.12065 -0.2794)
			(end -0.12065 -0.3048)
			(stroke
				(width 0.1)
				(type default)
			)
			(layer "B.Fab")
		)
		(fp_line
			(start 0.12065 -0.2794)
			(end -0.12065 -0.2794)
			(stroke
				(width 0.1)
				(type default)
			)
			(layer "B.Fab")
		)
		(fp_line
			(start -0.67945 -0.3048)
			(end -0.67945 0.3048)
			(stroke
				(width 0.1)
				(type default)
			)
			(layer "B.Fab")
		)
		(fp_line
			(start -0.12065 -0.3048)
			(end -0.67945 -0.3048)
			(stroke
				(width 0.1)
				(type default)
			)
			(layer "B.Fab")
		)
		(fp_line
			(start 0.12065 -0.305054)
			(end 0.12065 -0.2794)
			(stroke
				(width 0.1)
				(type default)
			)
			(layer "B.Fab")
		)
		(fp_line
			(start 0.67945 -0.305054)
			(end 0.12065 -0.305054)
			(stroke
				(width 0.1)
				(type default)
			)
			(layer "B.Fab")
		)
		(pad "1" smd circle
			(at 0.40005 0 90)
			(size 0 0)
			(layers "B.Cu" "B.Mask" "B.Paste")
			(net "PVDD18_S5_P0")
		)
		(pad "2" smd circle
			(at -0.40005 0 90)
			(size 0 0)
			(layers "B.Cu" "B.Mask" "B.Paste")
			(net "FAB_REV_ID0")
		)
	)
)
